(kicad_pcb
	(version 20260206)
	(generator "pcbnew")
	(generator_version "10.0")
	(general
		(thickness 1.6)
		(legacy_teardrops no)
	)
	(paper "A4")
	(title_block
		(title "01162023_DA0F0TEBIF0_F0T_Expander_BD_F_brd_V02_OCP.brd")
		(comment 1 "Grand Teton / footprints 1245-1251 of 9728")
	)
	(layers
		(0 "F.Cu" signal "TOP")
		(4 "In1.Cu" signal "GND")
		(6 "In2.Cu" signal "VCC")
		(8 "In3.Cu" signal "VCC1")
		(10 "In4.Cu" signal "GND1")
		(12 "In5.Cu" signal "IN1")
		(14 "In6.Cu" signal "GND2")
		(16 "In7.Cu" signal "IN2")
		(18 "In8.Cu" signal "GND3")
		(20 "In9.Cu" signal "IN3")
		(22 "In10.Cu" signal "GND4")
		(24 "In11.Cu" signal "IN4")
		(26 "In12.Cu" signal "GND5")
		(28 "In13.Cu" signal "IN5")
		(30 "In14.Cu" signal "GND6")
		(32 "In15.Cu" signal "IN6")
		(34 "In16.Cu" signal "GND7")
		(2 "B.Cu" signal "BOTTOM")
		(9 "F.Adhes" user "F.Adhesive")
		(11 "B.Adhes" user "B.Adhesive")
		(13 "F.Paste" user "Package Geometry/Pastemask Top")
		(15 "B.Paste" user "Package Geometry/Pastemask Bottom")
		(5 "F.SilkS" user "Ref Des/Silkscreen Top")
		(7 "B.SilkS" user "Ref Des/Silkscreen Bottom")
		(1 "F.Mask" user "Board Geometry/Soldermask Top")
		(3 "B.Mask" user "Board Geometry/Soldermask Bottom")
		(17 "Dwgs.User" user "User.Drawings")
		(19 "Cmts.User" user "User.Comments")
		(21 "Eco1.User" user "User.Eco1")
		(23 "Eco2.User" user "User.Eco2")
		(25 "Edge.Cuts" user "Board Geometry/Outline")
		(27 "Margin" user)
		(31 "F.CrtYd" user "Package Geometry/Place Bound Top")
		(29 "B.CrtYd" user "Package Geometry/Place Bound Bottom")
		(35 "F.Fab" user "Ref Des/Assembly Top")
		(33 "B.Fab" user "Ref Des/Assembly Bottom")
	)
	(footprint ""
		(layer "F.Cu")
		(at 285.326074 -37.929566 90)
		(property "Reference" "R5576"
			(at 0 0 90)
			(layer "F.SilkS")
			(hide yes)
			(effects
				(font
					(size 1.27 1.27)
				)
			)
		)
		(property "Value" ""
			(at 0 0 90)
			(layer "F.Fab")
			(effects
				(font
					(size 1.27 1.27)
				)
			)
		)
		(duplicate_pad_numbers_are_jumpers no)
		(fp_line
			(start 0.7874 -0.4064)
			(end 0.7874 0.4064)
			(stroke
				(width 0.1524)
				(type default)
			)
			(layer "F.SilkS")
		)
		(fp_line
			(start -0.7874 -0.4064)
			(end 0.7874 -0.4064)
			(stroke
				(width 0.1524)
				(type default)
			)
			(layer "F.SilkS")
		)
		(fp_line
			(start 0.7874 0.4064)
			(end -0.7874 0.4064)
			(stroke
				(width 0.1524)
				(type default)
			)
			(layer "F.SilkS")
		)
		(fp_line
			(start -0.7874 0.4064)
			(end -0.7874 -0.4064)
			(stroke
				(width 0.1524)
				(type default)
			)
			(layer "F.SilkS")
		)
		(fp_line
			(start -0.12065 -0.305054)
			(end -0.12065 -0.2794)
			(stroke
				(width 0.1)
				(type default)
			)
			(layer "F.Fab")
		)
		(fp_line
			(start -0.67945 -0.305054)
			(end -0.12065 -0.305054)
			(stroke
				(width 0.1)
				(type default)
			)
			(layer "F.Fab")
		)
		(fp_line
			(start 0.67945 -0.3048)
			(end 0.67945 0.3048)
			(stroke
				(width 0.1)
				(type default)
			)
			(layer "F.Fab")
		)
		(fp_line
			(start 0.12065 -0.3048)
			(end 0.67945 -0.3048)
			(stroke
				(width 0.1)
				(type default)
			)
			(layer "F.Fab")
		)
		(fp_line
			(start 0.12065 -0.2794)
			(end 0.12065 -0.3048)
			(stroke
				(width 0.1)
				(type default)
			)
			(layer "F.Fab")
		)
		(fp_line
			(start -0.12065 -0.2794)
			(end 0.12065 -0.2794)
			(stroke
				(width 0.1)
				(type default)
			)
			(layer "F.Fab")
		)
		(fp_line
			(start 0.120396 0.2794)
			(end -0.12065 0.2794)
			(stroke
				(width 0.1)
				(type default)
			)
			(layer "F.Fab")
		)
		(fp_line
			(start -0.12065 0.2794)
			(end -0.12065 0.3048)
			(stroke
				(width 0.1)
				(type default)
			)
			(layer "F.Fab")
		)
		(fp_line
			(start 0.67945 0.3048)
			(end 0.120396 0.3048)
			(stroke
				(width 0.1)
				(type default)
			)
			(layer "F.Fab")
		)
		(fp_line
			(start 0.120396 0.3048)
			(end 0.120396 0.2794)
			(stroke
				(width 0.1)
				(type default)
			)
			(layer "F.Fab")
		)
		(fp_line
			(start -0.12065 0.3048)
			(end -0.67945 0.3048)
			(stroke
				(width 0.1)
				(type default)
			)
			(layer "F.Fab")
		)
		(fp_line
			(start -0.67945 0.3048)
			(end -0.67945 -0.305054)
			(stroke
				(width 0.1)
				(type default)
			)
			(layer "F.Fab")
		)
		(pad "1" smd circle
			(at -0.40005 0 90)
			(size 0 0)
			(layers "F.Cu" "F.Mask" "F.Paste")
			(net "SSD10_AUX_P3V3_EN_R")
		)
		(pad "2" smd circle
			(at 0.40005 0 90)
			(size 0 0)
			(layers "F.Cu" "F.Mask" "F.Paste")
			(net "SSD10_AUX_P3V3_EN")
		)
	)
	(footprint ""
		(layer "F.Cu")
		(at 263.494012 -34.248852)
		(property "Reference" "R5680"
			(at 0 0 0)
			(layer "F.SilkS")
			(hide yes)
			(effects
				(font
					(size 1.27 1.27)
				)
			)
		)
		(property "Value" ""
			(at 0 0 0)
			(layer "F.Fab")
			(effects
				(font
					(size 1.27 1.27)
				)
			)
		)
		(duplicate_pad_numbers_are_jumpers no)
		(fp_line
			(start -0.7874 -0.4064)
			(end 0.7874 -0.4064)
			(stroke
				(width 0.1524)
				(type default)
			)
			(layer "F.SilkS")
		)
		(fp_line
			(start -0.7874 0.4064)
			(end -0.7874 -0.4064)
			(stroke
				(width 0.1524)
				(type default)
			)
			(layer "F.SilkS")
		)
		(fp_line
			(start 0.7874 -0.4064)
			(end 0.7874 0.4064)
			(stroke
				(width 0.1524)
				(type default)
			)
			(layer "F.SilkS")
		)
		(fp_line
			(start 0.7874 0.4064)
			(end -0.7874 0.4064)
			(stroke
				(width 0.1524)
				(type default)
			)
			(layer "F.SilkS")
		)
		(fp_line
			(start -0.67945 -0.305054)
			(end -0.12065 -0.305054)
			(stroke
				(width 0.1)
				(type default)
			)
			(layer "F.Fab")
		)
		(fp_line
			(start -0.67945 0.3048)
			(end -0.67945 -0.305054)
			(stroke
				(width 0.1)
				(type default)
			)
			(layer "F.Fab")
		)
		(fp_line
			(start -0.12065 -0.305054)
			(end -0.12065 -0.2794)
			(stroke
				(width 0.1)
				(type default)
			)
			(layer "F.Fab")
		)
		(fp_line
			(start -0.12065 -0.2794)
			(end 0.12065 -0.2794)
			(stroke
				(width 0.1)
				(type default)
			)
			(layer "F.Fab")
		)
		(fp_line
			(start -0.12065 0.2794)
			(end -0.12065 0.3048)
			(stroke
				(width 0.1)
				(type default)
			)
			(layer "F.Fab")
		)
		(fp_line
			(start -0.12065 0.3048)
			(end -0.67945 0.3048)
			(stroke
				(width 0.1)
				(type default)
			)
			(layer "F.Fab")
		)
		(fp_line
			(start 0.120396 0.2794)
			(end -0.12065 0.2794)
			(stroke
				(width 0.1)
				(type default)
			)
			(layer "F.Fab")
		)
		(fp_line
			(start 0.120396 0.3048)
			(end 0.120396 0.2794)
			(stroke
				(width 0.1)
				(type default)
			)
			(layer "F.Fab")
		)
		(fp_line
			(start 0.12065 -0.3048)
			(end 0.67945 -0.3048)
			(stroke
				(width 0.1)
				(type default)
			)
			(layer "F.Fab")
		)
		(fp_line
			(start 0.12065 -0.2794)
			(end 0.12065 -0.3048)
			(stroke
				(width 0.1)
				(type default)
			)
			(layer "F.Fab")
		)
		(fp_line
			(start 0.67945 -0.3048)
			(end 0.67945 0.3048)
			(stroke
				(width 0.1)
				(type default)
			)
			(layer "F.Fab")
		)
		(fp_line
			(start 0.67945 0.3048)
			(end 0.120396 0.3048)
			(stroke
				(width 0.1)
				(type default)
			)
			(layer "F.Fab")
		)
		(pad "1" smd circle
			(at -0.40005 0)
			(size 0 0)
			(layers "F.Cu" "F.Mask" "F.Paste")
			(net "RST_SMB_SSD9_ISO_N")
		)
		(pad "2" smd circle
			(at 0.40005 0)
			(size 0 0)
			(layers "F.Cu" "F.Mask" "F.Paste")
			(net "P3V3_SSD9")
		)
	)
	(footprint ""
		(layer "F.Cu")
		(at 69.792342 -29.139642 180)
		(property "Reference" "C87"
			(at 0 0 180)
			(layer "F.SilkS")
			(hide yes)
			(effects
				(font
					(size 1.27 1.27)
				)
			)
		)
		(property "Value" ""
			(at 0 0 180)
			(layer "F.Fab")
			(effects
				(font
					(size 1.27 1.27)
				)
			)
		)
		(duplicate_pad_numbers_are_jumpers no)
		(fp_line
			(start 0.299974 0.150114)
			(end -0.299974 0.150114)
			(stroke
				(width 0.1)
				(type default)
			)
			(layer "F.Fab")
		)
		(fp_line
			(start 0.299974 -0.150114)
			(end 0.299974 0.150114)
			(stroke
				(width 0.1)
				(type default)
			)
			(layer "F.Fab")
		)
		(fp_line
			(start -0.299974 0.150114)
			(end -0.299974 -0.150114)
			(stroke
				(width 0.1)
				(type default)
			)
			(layer "F.Fab")
		)
		(fp_line
			(start -0.299974 -0.150114)
			(end 0.299974 -0.150114)
			(stroke
				(width 0.1)
				(type default)
			)
			(layer "F.Fab")
		)
		(pad "1" smd rect
			(at -0.2667 0 180)
			(size 0.3048 0.381)
			(layers "F.Cu" "F.Mask" "F.Paste")
			(net "P5E_PEX0_STN2_TX_DP<36>")
		)
		(pad "2" smd rect
			(at 0.2667 0 180)
			(size 0.3048 0.381)
			(layers "F.Cu" "F.Mask" "F.Paste")
			(net "P5E_PEX0_STN2_TX_C_DP<36>")
		)
	)
	(footprint ""
		(layer "F.Cu")
		(at 215.464136 -185.702956 -90)
		(property "Reference" "U351"
			(at 0.57277 -1.895602 90)
			(unlocked yes)
			(layer "F.SilkS")
			(effects
				(font
					(size 0.7874 0.5842)
					(thickness 0.1524)
				)
			)
		)
		(property "Value" ""
			(at 0 0 270)
			(layer "F.Fab")
			(effects
				(font
					(size 1.27 1.27)
				)
			)
		)
		(duplicate_pad_numbers_are_jumpers no)
		(fp_line
			(start -1.7272 1.1176)
			(end -1.7272 -1.1176)
			(stroke
				(width 0.1524)
				(type default)
			)
			(layer "F.SilkS")
		)
		(fp_line
			(start 1.7272 1.1176)
			(end -1.7272 1.1176)
			(stroke
				(width 0.1524)
				(type default)
			)
			(layer "F.SilkS")
		)
		(fp_line
			(start 0 -0.7366)
			(end -0.254 -1.1176)
			(stroke
				(width 0.1524)
				(type default)
			)
			(layer "F.SilkS")
		)
		(fp_line
			(start -0.254 -1.1176)
			(end -1.7272 -1.1176)
			(stroke
				(width 0.1524)
				(type default)
			)
			(layer "F.SilkS")
		)
		(fp_line
			(start 0.254 -1.1176)
			(end 0 -0.7366)
			(stroke
				(width 0.1524)
				(type default)
			)
			(layer "F.SilkS")
		)
		(fp_line
			(start 1.7272 -1.1176)
			(end 1.7272 1.1176)
			(stroke
				(width 0.1524)
				(type default)
			)
			(layer "F.SilkS")
		)
		(fp_line
			(start 1.7272 -1.1176)
			(end 0.254 -1.1176)
			(stroke
				(width 0.1524)
				(type default)
			)
			(layer "F.SilkS")
		)
		(fp_poly
			(pts
				(xy -1.273048 -1.267968) (xy -1.654048 -2.029968) (xy -0.892048 -2.029968)
			)
			(stroke
				(width 0)
				(type default)
			)
			(fill yes)
			(layer "F.SilkS")
		)
		(fp_line
			(start -1.5748 1.1176)
			(end 1.5748 1.1176)
			(stroke
				(width 0.1)
				(type default)
			)
			(layer "F.Fab")
		)
		(fp_line
			(start 1.5748 1.1176)
			(end 1.5748 -1.1176)
			(stroke
				(width 0.1)
				(type default)
			)
			(layer "F.Fab")
		)
		(fp_line
			(start -1.5748 -1.1176)
			(end -1.5748 1.1176)
			(stroke
				(width 0.1)
				(type default)
			)
			(layer "F.Fab")
		)
		(fp_line
			(start 1.5748 -1.1176)
			(end -1.5748 -1.1176)
			(stroke
				(width 0.1)
				(type default)
			)
			(layer "F.Fab")
		)
		(fp_poly
			(pts
				(xy -1.9558 -0.649986) (xy -2.7178 -0.268986) (xy -2.7178 -1.030986)
			)
			(stroke
				(width 0)
				(type default)
			)
			(fill yes)
			(layer "F.Fab")
		)
		(pad "1" smd rect
			(at -0.999998 -0.649986 180)
			(size 0.3556 1.1176)
			(layers "F.Cu" "F.Mask" "F.Paste")
			(net "BIC_SEL_FLASH_SW0_R")
		)
		(pad "2" smd rect
			(at -0.999998 0 180)
			(size 0.3556 1.1176)
			(layers "F.Cu" "F.Mask" "F.Paste")
			(net "GND")
		)
		(pad "3" smd rect
			(at -0.999998 0.649986 180)
			(size 0.3556 1.1176)
			(layers "F.Cu" "F.Mask" "F.Paste")
			(net "BIC_SEL_FLASH_SW1_R")
		)
		(pad "4" smd rect
			(at 0.999998 0.649986 180)
			(size 0.3556 1.1176)
			(layers "F.Cu" "F.Mask" "F.Paste")
			(net "SEL_FLASH_PEX1_BUF")
		)
		(pad "5" smd rect
			(at 0.999998 0 180)
			(size 0.3556 1.1176)
			(layers "F.Cu" "F.Mask" "F.Paste")
			(net "P3V3_AUX")
		)
		(pad "6" smd rect
			(at 0.999998 -0.649986 180)
			(size 0.3556 1.1176)
			(layers "F.Cu" "F.Mask" "F.Paste")
			(net "SEL_FLASH_PEX0_BUF")
		)
	)
	(footprint ""
		(layer "F.Cu")
		(at 135.346948 -37.47516)
		(property "Reference" "R6063"
			(at 0 0 0)
			(layer "F.SilkS")
			(hide yes)
			(effects
				(font
					(size 1.27 1.27)
				)
			)
		)
		(property "Value" ""
			(at 0 0 0)
			(layer "F.Fab")
			(effects
				(font
					(size 1.27 1.27)
				)
			)
		)
		(duplicate_pad_numbers_are_jumpers no)
		(fp_line
			(start -0.7874 -0.4064)
			(end 0.7874 -0.4064)
			(stroke
				(width 0.1524)
				(type default)
			)
			(layer "F.SilkS")
		)
		(fp_line
			(start -0.7874 0.4064)
			(end -0.7874 -0.4064)
			(stroke
				(width 0.1524)
				(type default)
			)
			(layer "F.SilkS")
		)
		(fp_line
			(start 0.7874 -0.4064)
			(end 0.7874 0.4064)
			(stroke
				(width 0.1524)
				(type default)
			)
			(layer "F.SilkS")
		)
		(fp_line
			(start 0.7874 0.4064)
			(end -0.7874 0.4064)
			(stroke
				(width 0.1524)
				(type default)
			)
			(layer "F.SilkS")
		)
		(fp_line
			(start -0.67945 -0.305054)
			(end -0.12065 -0.305054)
			(stroke
				(width 0.1)
				(type default)
			)
			(layer "F.Fab")
		)
		(fp_line
			(start -0.67945 0.3048)
			(end -0.67945 -0.305054)
			(stroke
				(width 0.1)
				(type default)
			)
			(layer "F.Fab")
		)
		(fp_line
			(start -0.12065 -0.305054)
			(end -0.12065 -0.2794)
			(stroke
				(width 0.1)
				(type default)
			)
			(layer "F.Fab")
		)
		(fp_line
			(start -0.12065 -0.2794)
			(end 0.12065 -0.2794)
			(stroke
				(width 0.1)
				(type default)
			)
			(layer "F.Fab")
		)
		(fp_line
			(start -0.12065 0.2794)
			(end -0.12065 0.3048)
			(stroke
				(width 0.1)
				(type default)
			)
			(layer "F.Fab")
		)
		(fp_line
			(start -0.12065 0.3048)
			(end -0.67945 0.3048)
			(stroke
				(width 0.1)
				(type default)
			)
			(layer "F.Fab")
		)
		(fp_line
			(start 0.120396 0.2794)
			(end -0.12065 0.2794)
			(stroke
				(width 0.1)
				(type default)
			)
			(layer "F.Fab")
		)
		(fp_line
			(start 0.120396 0.3048)
			(end 0.120396 0.2794)
			(stroke
				(width 0.1)
				(type default)
			)
			(layer "F.Fab")
		)
		(fp_line
			(start 0.12065 -0.3048)
			(end 0.67945 -0.3048)
			(stroke
				(width 0.1)
				(type default)
			)
			(layer "F.Fab")
		)
		(fp_line
			(start 0.12065 -0.2794)
			(end 0.12065 -0.3048)
			(stroke
				(width 0.1)
				(type default)
			)
			(layer "F.Fab")
		)
		(fp_line
			(start 0.67945 -0.3048)
			(end 0.67945 0.3048)
			(stroke
				(width 0.1)
				(type default)
			)
			(layer "F.Fab")
		)
		(fp_line
			(start 0.67945 0.3048)
			(end 0.120396 0.3048)
			(stroke
				(width 0.1)
				(type default)
			)
			(layer "F.Fab")
		)
		(pad "1" smd circle
			(at -0.40005 0)
			(size 0 0)
			(layers "F.Cu" "F.Mask" "F.Paste")
			(net "P3V3_SSD5")
		)
		(pad "2" smd circle
			(at 0.40005 0)
			(size 0 0)
			(layers "F.Cu" "F.Mask" "F.Paste")
			(net "P3V3_SSD5_PG_G1")
		)
	)
	(footprint ""
		(layer "F.Cu")
		(at 82.847688 -40.037258 90)
		(property "Reference" "U366"
			(at 0.196342 2.497582 90)
			(unlocked yes)
			(layer "F.SilkS")
			(effects
				(font
					(size 0.7874 0.5842)
					(thickness 0.1524)
				)
			)
		)
		(property "Value" ""
			(at 0 0 90)
			(layer "F.Fab")
			(effects
				(font
					(size 1.27 1.27)
				)
			)
		)
		(duplicate_pad_numbers_are_jumpers no)
		(fp_line
			(start -1.949958 -1.610106)
			(end 1.949958 -1.610106)
			(stroke
				(width 0.1524)
				(type default)
			)
			(layer "F.SilkS")
		)
		(fp_line
			(start 1.949958 -1.560068)
			(end 1.949958 1.610106)
			(stroke
				(width 0.1524)
				(type default)
			)
			(layer "F.SilkS")
		)
		(fp_line
			(start 1.949958 1.610106)
			(end -1.949958 1.610106)
			(stroke
				(width 0.1524)
				(type default)
			)
			(layer "F.SilkS")
		)
		(fp_line
			(start -1.949958 1.610106)
			(end -1.949958 -1.610106)
			(stroke
				(width 0.1524)
				(type default)
			)
			(layer "F.SilkS")
		)
		(fp_line
			(start 0.750062 -1.560068)
			(end 0.750062 1.560068)
			(stroke
				(width 0.1)
				(type default)
			)
			(layer "F.Fab")
		)
		(fp_line
			(start -0.750062 -1.560068)
			(end 0.750062 -1.560068)
			(stroke
				(width 0.1)
				(type default)
			)
			(layer "F.Fab")
		)
		(fp_line
			(start 0.750062 1.560068)
			(end -0.750062 1.560068)
			(stroke
				(width 0.1)
				(type default)
			)
			(layer "F.Fab")
		)
		(fp_line
			(start -0.750062 1.560068)
			(end -0.750062 -1.560068)
			(stroke
				(width 0.1)
				(type default)
			)
			(layer "F.Fab")
		)
		(pad "D" smd rect
			(at 1.100074 0)
			(size 1.016 1.4224)
			(layers "F.Cu" "F.Mask" "F.Paste")
			(net "SSD3_AUX_P3V3_EN")
		)
		(pad "G" smd rect
			(at -1.100074 -0.94996)
			(size 1.016 1.4224)
			(layers "F.Cu" "F.Mask" "F.Paste")
			(net "PRSNT_SSD3_R1_N")
		)
		(pad "S" smd rect
			(at -1.100074 0.94996)
			(size 1.016 1.4224)
			(layers "F.Cu" "F.Mask" "F.Paste")
			(net "GND")
		)
	)
	(footprint ""
		(layer "F.Cu")
		(at 270.807942 -163.061396 180)
		(property "Reference" "R208"
			(at 0 0 180)
			(layer "F.SilkS")
			(hide yes)
			(effects
				(font
					(size 1.27 1.27)
				)
			)
		)
		(property "Value" ""
			(at 0 0 180)
			(layer "F.Fab")
			(effects
				(font
					(size 1.27 1.27)
				)
			)
		)
		(duplicate_pad_numbers_are_jumpers no)
		(fp_line
			(start 0.7874 0.4064)
			(end -0.7874 0.4064)
			(stroke
				(width 0.1524)
				(type default)
			)
			(layer "F.SilkS")
		)
		(fp_line
			(start 0.7874 -0.4064)
			(end 0.7874 0.4064)
			(stroke
				(width 0.1524)
				(type default)
			)
			(layer "F.SilkS")
		)
		(fp_line
			(start -0.7874 0.4064)
			(end -0.7874 -0.4064)
			(stroke
				(width 0.1524)
				(type default)
			)
			(layer "F.SilkS")
		)
		(fp_line
			(start -0.7874 -0.4064)
			(end 0.7874 -0.4064)
			(stroke
				(width 0.1524)
				(type default)
			)
			(layer "F.SilkS")
		)
		(fp_line
			(start 0.67945 0.3048)
			(end 0.120396 0.3048)
			(stroke
				(width 0.1)
				(type default)
			)
			(layer "F.Fab")
		)
		(fp_line
			(start 0.67945 -0.3048)
			(end 0.67945 0.3048)
			(stroke
				(width 0.1)
				(type default)
			)
			(layer "F.Fab")
		)
		(fp_line
			(start 0.12065 -0.2794)
			(end 0.12065 -0.3048)
			(stroke
				(width 0.1)
				(type default)
			)
			(layer "F.Fab")
		)
		(fp_line
			(start 0.12065 -0.3048)
			(end 0.67945 -0.3048)
			(stroke
				(width 0.1)
				(type default)
			)
			(layer "F.Fab")
		)
		(fp_line
			(start 0.120396 0.3048)
			(end 0.120396 0.2794)
			(stroke
				(width 0.1)
				(type default)
			)
			(layer "F.Fab")
		)
		(fp_line
			(start 0.120396 0.2794)
			(end -0.12065 0.2794)
			(stroke
				(width 0.1)
				(type default)
			)
			(layer "F.Fab")
		)
		(fp_line
			(start -0.12065 0.3048)
			(end -0.67945 0.3048)
			(stroke
				(width 0.1)
				(type default)
			)
			(layer "F.Fab")
		)
		(fp_line
			(start -0.12065 0.2794)
			(end -0.12065 0.3048)
			(stroke
				(width 0.1)
				(type default)
			)
			(layer "F.Fab")
		)
		(fp_line
			(start -0.12065 -0.2794)
			(end 0.12065 -0.2794)
			(stroke
				(width 0.1)
				(type default)
			)
			(layer "F.Fab")
		)
		(fp_line
			(start -0.12065 -0.305054)
			(end -0.12065 -0.2794)
			(stroke
				(width 0.1)
				(type default)
			)
			(layer "F.Fab")
		)
		(fp_line
			(start -0.67945 0.3048)
			(end -0.67945 -0.305054)
			(stroke
				(width 0.1)
				(type default)
			)
			(layer "F.Fab")
		)
		(fp_line
			(start -0.67945 -0.305054)
			(end -0.12065 -0.305054)
			(stroke
				(width 0.1)
				(type default)
			)
			(layer "F.Fab")
		)
		(pad "1" smd circle
			(at -0.40005 0 180)
			(size 0 0)
			(layers "F.Cu" "F.Mask" "F.Paste")
			(net "PWRGD_NIC4_PWR_GOOD")
		)
		(pad "2" smd circle
			(at 0.40005 0 180)
			(size 0 0)
			(layers "F.Cu" "F.Mask" "F.Paste")
			(net "PWRGD_NIC4_PWR_GOOD_R")
		)
	)
)
